(kicad_pcb
	(version 20260206)
	(generator "pcbnew")
	(generator_version "10.0")
	(general
		(thickness 1.6)
		(legacy_teardrops no)
	)
	(paper "A4")
	(title_block
		(title "01162023_DA0F0TEBIF0_F0T_Expander_BD_F_brd_V02_OCP.brd")
		(comment 1 "Grand Teton / footprints 519-528 of 9728")
	)
	(layers
		(0 "F.Cu" signal "TOP")
		(4 "In1.Cu" signal "GND")
		(6 "In2.Cu" signal "VCC")
		(8 "In3.Cu" signal "VCC1")
		(10 "In4.Cu" signal "GND1")
		(12 "In5.Cu" signal "IN1")
		(14 "In6.Cu" signal "GND2")
		(16 "In7.Cu" signal "IN2")
		(18 "In8.Cu" signal "GND3")
		(20 "In9.Cu" signal "IN3")
		(22 "In10.Cu" signal "GND4")
		(24 "In11.Cu" signal "IN4")
		(26 "In12.Cu" signal "GND5")
		(28 "In13.Cu" signal "IN5")
		(30 "In14.Cu" signal "GND6")
		(32 "In15.Cu" signal "IN6")
		(34 "In16.Cu" signal "GND7")
		(2 "B.Cu" signal "BOTTOM")
		(9 "F.Adhes" user "F.Adhesive")
		(11 "B.Adhes" user "B.Adhesive")
		(13 "F.Paste" user "Package Geometry/Pastemask Top")
		(15 "B.Paste" user "Package Geometry/Pastemask Bottom")
		(5 "F.SilkS" user "Ref Des/Silkscreen Top")
		(7 "B.SilkS" user "Ref Des/Silkscreen Bottom")
		(1 "F.Mask" user "Board Geometry/Soldermask Top")
		(3 "B.Mask" user "Board Geometry/Soldermask Bottom")
		(17 "Dwgs.User" user "User.Drawings")
		(19 "Cmts.User" user "User.Comments")
		(21 "Eco1.User" user "User.Eco1")
		(23 "Eco2.User" user "User.Eco2")
		(25 "Edge.Cuts" user "Board Geometry/Outline")
		(27 "Margin" user)
		(31 "F.CrtYd" user "Package Geometry/Place Bound Top")
		(29 "B.CrtYd" user "Package Geometry/Place Bound Bottom")
		(35 "F.Fab" user "Ref Des/Assembly Top")
		(33 "B.Fab" user "Ref Des/Assembly Bottom")
	)
	(footprint ""
		(layer "F.Cu")
		(at 154.567636 -218.02852)
		(property "Reference" "ME1"
			(at 0 0 0)
			(layer "F.SilkS")
			(hide yes)
			(effects
				(font
					(size 1.27 1.27)
				)
			)
		)
		(property "Value" ""
			(at 0 0 0)
			(layer "F.Fab")
			(effects
				(font
					(size 1.27 1.27)
				)
			)
		)
		(duplicate_pad_numbers_are_jumpers no)
	)
	(footprint ""
		(layer "F.Cu")
		(at 62.261242 -343.952322 90)
		(property "Reference" "C130"
			(at 0 0 90)
			(layer "F.SilkS")
			(hide yes)
			(effects
				(font
					(size 1.27 1.27)
				)
			)
		)
		(property "Value" ""
			(at 0 0 90)
			(layer "F.Fab")
			(effects
				(font
					(size 1.27 1.27)
				)
			)
		)
		(duplicate_pad_numbers_are_jumpers no)
		(fp_line
			(start 0.299974 -0.150114)
			(end 0.299974 0.150114)
			(stroke
				(width 0.1)
				(type default)
			)
			(layer "F.Fab")
		)
		(fp_line
			(start -0.299974 -0.150114)
			(end 0.299974 -0.150114)
			(stroke
				(width 0.1)
				(type default)
			)
			(layer "F.Fab")
		)
		(fp_line
			(start 0.299974 0.150114)
			(end -0.299974 0.150114)
			(stroke
				(width 0.1)
				(type default)
			)
			(layer "F.Fab")
		)
		(fp_line
			(start -0.299974 0.150114)
			(end -0.299974 -0.150114)
			(stroke
				(width 0.1)
				(type default)
			)
			(layer "F.Fab")
		)
		(pad "1" smd rect
			(at -0.2667 0 90)
			(size 0.3048 0.381)
			(layers "F.Cu" "F.Mask" "F.Paste")
			(net "P5E_PEX0_STN6_TX_DN<111>")
		)
		(pad "2" smd rect
			(at 0.2667 0 90)
			(size 0.3048 0.381)
			(layers "F.Cu" "F.Mask" "F.Paste")
			(net "P5E_PEX0_STN6_TX_C_DN<111>")
		)
	)
	(footprint ""
		(layer "F.Cu")
		(at 333.762604 -100.406708 -90)
		(property "Reference" "PC319"
			(at 0 0 270)
			(layer "F.SilkS")
			(hide yes)
			(effects
				(font
					(size 1.27 1.27)
				)
			)
		)
		(property "Value" ""
			(at 0 0 270)
			(layer "F.Fab")
			(effects
				(font
					(size 1.27 1.27)
				)
			)
		)
		(duplicate_pad_numbers_are_jumpers no)
		(fp_line
			(start -1.524 0.762)
			(end -1.524 -0.762)
			(stroke
				(width 0.1524)
				(type default)
			)
			(layer "F.SilkS")
		)
		(fp_line
			(start 1.524 0.762)
			(end -1.524 0.762)
			(stroke
				(width 0.1524)
				(type default)
			)
			(layer "F.SilkS")
		)
		(fp_line
			(start -1.524 -0.762)
			(end 1.524 -0.762)
			(stroke
				(width 0.1524)
				(type default)
			)
			(layer "F.SilkS")
		)
		(fp_line
			(start 1.524 -0.762)
			(end 1.524 0.762)
			(stroke
				(width 0.1524)
				(type default)
			)
			(layer "F.SilkS")
		)
		(fp_line
			(start -1.1049 0.724916)
			(end 1.1049 0.724916)
			(stroke
				(width 0.1)
				(type default)
			)
			(layer "F.Fab")
		)
		(fp_line
			(start 1.1049 0.724916)
			(end 1.1049 -0.724916)
			(stroke
				(width 0.1)
				(type default)
			)
			(layer "F.Fab")
		)
		(fp_line
			(start -1.1049 -0.724916)
			(end -1.1049 0.724916)
			(stroke
				(width 0.1)
				(type default)
			)
			(layer "F.Fab")
		)
		(fp_line
			(start 1.1049 -0.724916)
			(end -1.1049 -0.724916)
			(stroke
				(width 0.1)
				(type default)
			)
			(layer "F.Fab")
		)
		(pad "1" smd rect
			(at -0.889 0 90)
			(size 1.016 1.27)
			(layers "F.Cu" "F.Mask" "F.Paste")
			(net "GND")
		)
		(pad "2" smd rect
			(at 0.889 0 90)
			(size 1.016 1.27)
			(layers "F.Cu" "F.Mask" "F.Paste")
			(net "P12V_AUX")
		)
	)
	(footprint ""
		(layer "F.Cu")
		(at 280.307542 -350.098614 90)
		(property "Reference" "C601"
			(at 0 0 90)
			(layer "F.SilkS")
			(hide yes)
			(effects
				(font
					(size 1.27 1.27)
				)
			)
		)
		(property "Value" ""
			(at 0 0 90)
			(layer "F.Fab")
			(effects
				(font
					(size 1.27 1.27)
				)
			)
		)
		(duplicate_pad_numbers_are_jumpers no)
		(fp_line
			(start 0.299974 -0.150114)
			(end 0.299974 0.150114)
			(stroke
				(width 0.1)
				(type default)
			)
			(layer "F.Fab")
		)
		(fp_line
			(start -0.299974 -0.150114)
			(end 0.299974 -0.150114)
			(stroke
				(width 0.1)
				(type default)
			)
			(layer "F.Fab")
		)
		(fp_line
			(start 0.299974 0.150114)
			(end -0.299974 0.150114)
			(stroke
				(width 0.1)
				(type default)
			)
			(layer "F.Fab")
		)
		(fp_line
			(start -0.299974 0.150114)
			(end -0.299974 -0.150114)
			(stroke
				(width 0.1)
				(type default)
			)
			(layer "F.Fab")
		)
		(pad "1" smd rect
			(at -0.2667 0 90)
			(size 0.3048 0.381)
			(layers "F.Cu" "F.Mask" "F.Paste")
			(net "P5E_PEX2_STN7_TX_DP<118>")
		)
		(pad "2" smd rect
			(at 0.2667 0 90)
			(size 0.3048 0.381)
			(layers "F.Cu" "F.Mask" "F.Paste")
			(net "P5E_PEX2_STN7_TX_C_DP<118>")
		)
	)
	(footprint ""
		(layer "F.Cu")
		(at 31.698692 -309.570628 45)
		(property "Reference" "R1169"
			(at 0 0 45)
			(layer "F.SilkS")
			(hide yes)
			(effects
				(font
					(size 1.27 1.27)
				)
			)
		)
		(property "Value" ""
			(at 0 0 45)
			(layer "F.Fab")
			(effects
				(font
					(size 1.27 1.27)
				)
			)
		)
		(duplicate_pad_numbers_are_jumpers no)
		(fp_line
			(start -0.787389 -0.406267)
			(end 0.787389 -0.406267)
			(stroke
				(width 0.1524)
				(type default)
			)
			(layer "F.SilkS")
		)
		(fp_line
			(start -0.787389 0.406267)
			(end -0.787389 -0.406267)
			(stroke
				(width 0.1524)
				(type default)
			)
			(layer "F.SilkS")
		)
		(fp_line
			(start 0.787389 -0.406267)
			(end 0.787389 0.406267)
			(stroke
				(width 0.1524)
				(type default)
			)
			(layer "F.SilkS")
		)
		(fp_line
			(start 0.787389 0.406267)
			(end -0.787389 0.406267)
			(stroke
				(width 0.1524)
				(type default)
			)
			(layer "F.SilkS")
		)
		(fp_line
			(start -0.679446 -0.305149)
			(end -0.120695 -0.304969)
			(stroke
				(width 0.1)
				(type default)
			)
			(layer "F.Fab")
		)
		(fp_line
			(start -0.120695 -0.304969)
			(end -0.120695 -0.279466)
			(stroke
				(width 0.1)
				(type default)
			)
			(layer "F.Fab")
		)
		(fp_line
			(start -0.120695 -0.279466)
			(end 0.120695 -0.279466)
			(stroke
				(width 0.1)
				(type default)
			)
			(layer "F.Fab")
		)
		(fp_line
			(start -0.679446 0.30479)
			(end -0.679446 -0.305149)
			(stroke
				(width 0.1)
				(type default)
			)
			(layer "F.Fab")
		)
		(fp_line
			(start 0.120515 -0.30479)
			(end 0.679446 -0.30479)
			(stroke
				(width 0.1)
				(type default)
			)
			(layer "F.Fab")
		)
		(fp_line
			(start 0.120695 -0.279466)
			(end 0.120515 -0.30479)
			(stroke
				(width 0.1)
				(type default)
			)
			(layer "F.Fab")
		)
		(fp_line
			(start -0.120695 0.279466)
			(end -0.120515 0.30479)
			(stroke
				(width 0.1)
				(type default)
			)
			(layer "F.Fab")
		)
		(fp_line
			(start -0.120515 0.30479)
			(end -0.679446 0.30479)
			(stroke
				(width 0.1)
				(type default)
			)
			(layer "F.Fab")
		)
		(fp_line
			(start 0.679446 -0.30479)
			(end 0.679446 0.30479)
			(stroke
				(width 0.1)
				(type default)
			)
			(layer "F.Fab")
		)
		(fp_line
			(start 0.120335 0.279466)
			(end -0.120695 0.279466)
			(stroke
				(width 0.1)
				(type default)
			)
			(layer "F.Fab")
		)
		(fp_line
			(start 0.120515 0.30479)
			(end 0.120335 0.279466)
			(stroke
				(width 0.1)
				(type default)
			)
			(layer "F.Fab")
		)
		(fp_line
			(start 0.679446 0.30479)
			(end 0.120515 0.30479)
			(stroke
				(width 0.1)
				(type default)
			)
			(layer "F.Fab")
		)
		(pad "1" smd circle
			(at -0.40005 0 45)
			(size 0 0)
			(layers "F.Cu" "F.Mask" "F.Paste")
			(net "GND")
		)
		(pad "2" smd circle
			(at 0.40005 0 45)
			(size 0 0)
			(layers "F.Cu" "F.Mask" "F.Paste")
			(net "PEX0_DBG_MODE0")
		)
	)
	(footprint ""
		(layer "F.Cu")
		(at 38.608 -155.3464 180)
		(property "Reference" "R14"
			(at 0 0 180)
			(layer "F.SilkS")
			(hide yes)
			(effects
				(font
					(size 1.27 1.27)
				)
			)
		)
		(property "Value" ""
			(at 0 0 180)
			(layer "F.Fab")
			(effects
				(font
					(size 1.27 1.27)
				)
			)
		)
		(duplicate_pad_numbers_are_jumpers no)
		(fp_line
			(start 0.7874 0.4064)
			(end -0.7874 0.4064)
			(stroke
				(width 0.1524)
				(type default)
			)
			(layer "F.SilkS")
		)
		(fp_line
			(start 0.7874 -0.4064)
			(end 0.7874 0.4064)
			(stroke
				(width 0.1524)
				(type default)
			)
			(layer "F.SilkS")
		)
		(fp_line
			(start -0.7874 0.4064)
			(end -0.7874 -0.4064)
			(stroke
				(width 0.1524)
				(type default)
			)
			(layer "F.SilkS")
		)
		(fp_line
			(start -0.7874 -0.4064)
			(end 0.7874 -0.4064)
			(stroke
				(width 0.1524)
				(type default)
			)
			(layer "F.SilkS")
		)
		(fp_line
			(start 0.67945 0.3048)
			(end 0.120396 0.3048)
			(stroke
				(width 0.1)
				(type default)
			)
			(layer "F.Fab")
		)
		(fp_line
			(start 0.67945 -0.3048)
			(end 0.67945 0.3048)
			(stroke
				(width 0.1)
				(type default)
			)
			(layer "F.Fab")
		)
		(fp_line
			(start 0.12065 -0.2794)
			(end 0.12065 -0.3048)
			(stroke
				(width 0.1)
				(type default)
			)
			(layer "F.Fab")
		)
		(fp_line
			(start 0.12065 -0.3048)
			(end 0.67945 -0.3048)
			(stroke
				(width 0.1)
				(type default)
			)
			(layer "F.Fab")
		)
		(fp_line
			(start 0.120396 0.3048)
			(end 0.120396 0.2794)
			(stroke
				(width 0.1)
				(type default)
			)
			(layer "F.Fab")
		)
		(fp_line
			(start 0.120396 0.2794)
			(end -0.12065 0.2794)
			(stroke
				(width 0.1)
				(type default)
			)
			(layer "F.Fab")
		)
		(fp_line
			(start -0.12065 0.3048)
			(end -0.67945 0.3048)
			(stroke
				(width 0.1)
				(type default)
			)
			(layer "F.Fab")
		)
		(fp_line
			(start -0.12065 0.2794)
			(end -0.12065 0.3048)
			(stroke
				(width 0.1)
				(type default)
			)
			(layer "F.Fab")
		)
		(fp_line
			(start -0.12065 -0.2794)
			(end 0.12065 -0.2794)
			(stroke
				(width 0.1)
				(type default)
			)
			(layer "F.Fab")
		)
		(fp_line
			(start -0.12065 -0.305054)
			(end -0.12065 -0.2794)
			(stroke
				(width 0.1)
				(type default)
			)
			(layer "F.Fab")
		)
		(fp_line
			(start -0.67945 0.3048)
			(end -0.67945 -0.305054)
			(stroke
				(width 0.1)
				(type default)
			)
			(layer "F.Fab")
		)
		(fp_line
			(start -0.67945 -0.305054)
			(end -0.12065 -0.305054)
			(stroke
				(width 0.1)
				(type default)
			)
			(layer "F.Fab")
		)
		(pad "1" smd circle
			(at -0.40005 0 180)
			(size 0 0)
			(layers "F.Cu" "F.Mask" "F.Paste")
			(net "NIC0_CLK")
		)
		(pad "2" smd circle
			(at 0.40005 0 180)
			(size 0 0)
			(layers "F.Cu" "F.Mask" "F.Paste")
			(net "GND")
		)
	)
	(footprint ""
		(layer "F.Cu")
		(at 245.421658 -129.799334 180)
		(property "Reference" "PD92"
			(at 5.036058 2.584196 0)
			(unlocked yes)
			(layer "F.SilkS")
			(effects
				(font
					(size 0.7874 0.5842)
					(thickness 0.1524)
				)
				(justify left)
			)
		)
		(property "Value" ""
			(at 0 0 180)
			(layer "F.Fab")
			(effects
				(font
					(size 1.27 1.27)
				)
			)
		)
		(duplicate_pad_numbers_are_jumpers no)
		(fp_line
			(start 4.240784 1.970024)
			(end 4.240784 -1.970024)
			(stroke
				(width 0.1524)
				(type default)
			)
			(layer "F.SilkS")
		)
		(fp_line
			(start 4.240784 -1.970024)
			(end -3.656584 -1.970024)
			(stroke
				(width 0.1524)
				(type default)
			)
			(layer "F.SilkS")
		)
		(fp_line
			(start -3.656584 1.970024)
			(end 4.240784 1.970024)
			(stroke
				(width 0.1524)
				(type default)
			)
			(layer "F.SilkS")
		)
		(fp_line
			(start -3.656584 -1.970024)
			(end -3.656584 1.970024)
			(stroke
				(width 0.1524)
				(type default)
			)
			(layer "F.SilkS")
		)
		(fp_poly
			(pts
				(xy 3.580384 1.970024) (xy 3.580384 -1.970024) (xy 4.240784 -1.970024) (xy 4.240784 1.970024)
			)
			(stroke
				(width 0)
				(type default)
			)
			(fill yes)
			(layer "F.SilkS")
		)
		(fp_line
			(start 2.3749 1.970024)
			(end 2.3749 -1.970024)
			(stroke
				(width 0.1)
				(type default)
			)
			(layer "F.Fab")
		)
		(fp_line
			(start 2.3749 -1.970024)
			(end -2.3749 -1.970024)
			(stroke
				(width 0.1)
				(type default)
			)
			(layer "F.Fab")
		)
		(fp_line
			(start -2.3749 1.970024)
			(end 2.3749 1.970024)
			(stroke
				(width 0.1)
				(type default)
			)
			(layer "F.Fab")
		)
		(fp_line
			(start -2.3749 -1.970024)
			(end -2.3749 1.970024)
			(stroke
				(width 0.1)
				(type default)
			)
			(layer "F.Fab")
		)
		(fp_text user "-"
			(at 4.1656 -0.23495 180)
			(unlocked yes)
			(layer "F.Fab")
			(effects
				(font
					(size 1.905 1.4224)
					(thickness 0.1524)
				)
				(justify left)
			)
		)
		(fp_text user "+"
			(at -4.9784 -0.23495 180)
			(unlocked yes)
			(layer "F.Fab")
			(effects
				(font
					(size 1.905 1.4224)
					(thickness 0.1524)
				)
				(justify left)
			)
		)
		(pad "A" smd rect
			(at -2.450084 0 180)
			(size 2.159 2.2606)
			(layers "F.Cu" "F.Mask" "F.Paste")
			(net "GND")
		)
		(pad "C" smd rect
			(at 2.450084 0 180)
			(size 2.159 2.2606)
			(layers "F.Cu" "F.Mask" "F.Paste")
			(net "P12V_AUX")
		)
	)
	(footprint ""
		(layer "F.Cu")
		(at 365.506 -195.707 180)
		(property "Reference" "R4691"
			(at 0 0 180)
			(layer "F.SilkS")
			(hide yes)
			(effects
				(font
					(size 1.27 1.27)
				)
			)
		)
		(property "Value" ""
			(at 0 0 180)
			(layer "F.Fab")
			(effects
				(font
					(size 1.27 1.27)
				)
			)
		)
		(duplicate_pad_numbers_are_jumpers no)
		(fp_line
			(start 0.7874 0.4064)
			(end -0.7874 0.4064)
			(stroke
				(width 0.1524)
				(type default)
			)
			(layer "F.SilkS")
		)
		(fp_line
			(start 0.7874 -0.4064)
			(end 0.7874 0.4064)
			(stroke
				(width 0.1524)
				(type default)
			)
			(layer "F.SilkS")
		)
		(fp_line
			(start -0.7874 0.4064)
			(end -0.7874 -0.4064)
			(stroke
				(width 0.1524)
				(type default)
			)
			(layer "F.SilkS")
		)
		(fp_line
			(start -0.7874 -0.4064)
			(end 0.7874 -0.4064)
			(stroke
				(width 0.1524)
				(type default)
			)
			(layer "F.SilkS")
		)
		(fp_line
			(start 0.67945 0.3048)
			(end 0.120396 0.3048)
			(stroke
				(width 0.1)
				(type default)
			)
			(layer "F.Fab")
		)
		(fp_line
			(start 0.67945 -0.3048)
			(end 0.67945 0.3048)
			(stroke
				(width 0.1)
				(type default)
			)
			(layer "F.Fab")
		)
		(fp_line
			(start 0.12065 -0.2794)
			(end 0.12065 -0.3048)
			(stroke
				(width 0.1)
				(type default)
			)
			(layer "F.Fab")
		)
		(fp_line
			(start 0.12065 -0.3048)
			(end 0.67945 -0.3048)
			(stroke
				(width 0.1)
				(type default)
			)
			(layer "F.Fab")
		)
		(fp_line
			(start 0.120396 0.3048)
			(end 0.120396 0.2794)
			(stroke
				(width 0.1)
				(type default)
			)
			(layer "F.Fab")
		)
		(fp_line
			(start 0.120396 0.2794)
			(end -0.12065 0.2794)
			(stroke
				(width 0.1)
				(type default)
			)
			(layer "F.Fab")
		)
		(fp_line
			(start -0.12065 0.3048)
			(end -0.67945 0.3048)
			(stroke
				(width 0.1)
				(type default)
			)
			(layer "F.Fab")
		)
		(fp_line
			(start -0.12065 0.2794)
			(end -0.12065 0.3048)
			(stroke
				(width 0.1)
				(type default)
			)
			(layer "F.Fab")
		)
		(fp_line
			(start -0.12065 -0.2794)
			(end 0.12065 -0.2794)
			(stroke
				(width 0.1)
				(type default)
			)
			(layer "F.Fab")
		)
		(fp_line
			(start -0.12065 -0.305054)
			(end -0.12065 -0.2794)
			(stroke
				(width 0.1)
				(type default)
			)
			(layer "F.Fab")
		)
		(fp_line
			(start -0.67945 0.3048)
			(end -0.67945 -0.305054)
			(stroke
				(width 0.1)
				(type default)
			)
			(layer "F.Fab")
		)
		(fp_line
			(start -0.67945 -0.305054)
			(end -0.12065 -0.305054)
			(stroke
				(width 0.1)
				(type default)
			)
			(layer "F.Fab")
		)
		(pad "1" smd circle
			(at -0.40005 0 180)
			(size 0 0)
			(layers "F.Cu" "F.Mask" "F.Paste")
			(net "SSD5_PEX_PWR_EN")
		)
		(pad "2" smd circle
			(at 0.40005 0 180)
			(size 0 0)
			(layers "F.Cu" "F.Mask" "F.Paste")
			(net "SSD5_PEX_PWR_EN_R")
		)
	)
	(footprint ""
		(layer "F.Cu")
		(at 296.766742 -350.098614 90)
		(property "Reference" "C2368"
			(at 0 0 90)
			(layer "F.SilkS")
			(hide yes)
			(effects
				(font
					(size 1.27 1.27)
				)
			)
		)
		(property "Value" ""
			(at 0 0 90)
			(layer "F.Fab")
			(effects
				(font
					(size 1.27 1.27)
				)
			)
		)
		(duplicate_pad_numbers_are_jumpers no)
		(fp_line
			(start 0.299974 -0.150114)
			(end 0.299974 0.150114)
			(stroke
				(width 0.1)
				(type default)
			)
			(layer "F.Fab")
		)
		(fp_line
			(start -0.299974 -0.150114)
			(end 0.299974 -0.150114)
			(stroke
				(width 0.1)
				(type default)
			)
			(layer "F.Fab")
		)
		(fp_line
			(start 0.299974 0.150114)
			(end -0.299974 0.150114)
			(stroke
				(width 0.1)
				(type default)
			)
			(layer "F.Fab")
		)
		(fp_line
			(start -0.299974 0.150114)
			(end -0.299974 -0.150114)
			(stroke
				(width 0.1)
				(type default)
			)
			(layer "F.Fab")
		)
		(pad "1" smd rect
			(at -0.2667 0 90)
			(size 0.3048 0.381)
			(layers "F.Cu" "F.Mask" "F.Paste")
			(net "P5E_PEX2_STN4_TX_DN<66>")
		)
		(pad "2" smd rect
			(at 0.2667 0 90)
			(size 0.3048 0.381)
			(layers "F.Cu" "F.Mask" "F.Paste")
			(net "P5E_PEX2_STN4_TX_C_DN<66>")
		)
	)
	(footprint ""
		(layer "F.Cu")
		(at 324.913244 -343.952322 90)
		(property "Reference" "C561"
			(at 0 0 90)
			(layer "F.SilkS")
			(hide yes)
			(effects
				(font
					(size 1.27 1.27)
				)
			)
		)
		(property "Value" ""
			(at 0 0 90)
			(layer "F.Fab")
			(effects
				(font
					(size 1.27 1.27)
				)
			)
		)
		(duplicate_pad_numbers_are_jumpers no)
		(fp_line
			(start 0.299974 -0.150114)
			(end 0.299974 0.150114)
			(stroke
				(width 0.1)
				(type default)
			)
			(layer "F.Fab")
		)
		(fp_line
			(start -0.299974 -0.150114)
			(end 0.299974 -0.150114)
			(stroke
				(width 0.1)
				(type default)
			)
			(layer "F.Fab")
		)
		(fp_line
			(start 0.299974 0.150114)
			(end -0.299974 0.150114)
			(stroke
				(width 0.1)
				(type default)
			)
			(layer "F.Fab")
		)
		(fp_line
			(start -0.299974 0.150114)
			(end -0.299974 -0.150114)
			(stroke
				(width 0.1)
				(type default)
			)
			(layer "F.Fab")
		)
		(pad "1" smd rect
			(at -0.2667 0 90)
			(size 0.3048 0.381)
			(layers "F.Cu" "F.Mask" "F.Paste")
			(net "P5E_PEX2_STN6_TX_DP<106>")
		)
		(pad "2" smd rect
			(at 0.2667 0 90)
			(size 0.3048 0.381)
			(layers "F.Cu" "F.Mask" "F.Paste")
			(net "P5E_PEX2_STN6_TX_C_DP<106>")
		)
	)
)
